(kicad_pcb
	(version 20260206)
	(generator "pcbnew")
	(generator_version "10.0")
	(general
		(thickness 1.6)
		(legacy_teardrops no)
	)
	(paper "A4")
	(title_block
		(title "01162023_DA0F0TEBIF0_F0T_Expander_BD_F_brd_V02_OCP.brd")
		(comment 1 "Grand Teton / footprints 3499-3504 of 9728")
	)
	(layers
		(0 "F.Cu" signal "TOP")
		(4 "In1.Cu" signal "GND")
		(6 "In2.Cu" signal "VCC")
		(8 "In3.Cu" signal "VCC1")
		(10 "In4.Cu" signal "GND1")
		(12 "In5.Cu" signal "IN1")
		(14 "In6.Cu" signal "GND2")
		(16 "In7.Cu" signal "IN2")
		(18 "In8.Cu" signal "GND3")
		(20 "In9.Cu" signal "IN3")
		(22 "In10.Cu" signal "GND4")
		(24 "In11.Cu" signal "IN4")
		(26 "In12.Cu" signal "GND5")
		(28 "In13.Cu" signal "IN5")
		(30 "In14.Cu" signal "GND6")
		(32 "In15.Cu" signal "IN6")
		(34 "In16.Cu" signal "GND7")
		(2 "B.Cu" signal "BOTTOM")
		(9 "F.Adhes" user "F.Adhesive")
		(11 "B.Adhes" user "B.Adhesive")
		(13 "F.Paste" user "Package Geometry/Pastemask Top")
		(15 "B.Paste" user "Package Geometry/Pastemask Bottom")
		(5 "F.SilkS" user "Ref Des/Silkscreen Top")
		(7 "B.SilkS" user "Ref Des/Silkscreen Bottom")
		(1 "F.Mask" user "Board Geometry/Soldermask Top")
		(3 "B.Mask" user "Board Geometry/Soldermask Bottom")
		(17 "Dwgs.User" user "User.Drawings")
		(19 "Cmts.User" user "User.Comments")
		(21 "Eco1.User" user "User.Eco1")
		(23 "Eco2.User" user "User.Eco2")
		(25 "Edge.Cuts" user "Board Geometry/Outline")
		(27 "Margin" user)
		(31 "F.CrtYd" user "Package Geometry/Place Bound Top")
		(29 "B.CrtYd" user "Package Geometry/Place Bound Bottom")
		(35 "F.Fab" user "Ref Des/Assembly Top")
		(33 "B.Fab" user "Ref Des/Assembly Bottom")
	)
	(footprint ""
		(layer "F.Cu")
		(at 295.008554 -158.080202 90)
		(property "Reference" "R2475"
			(at 0 0 90)
			(layer "F.SilkS")
			(hide yes)
			(effects
				(font
					(size 1.27 1.27)
				)
			)
		)
		(property "Value" ""
			(at 0 0 90)
			(layer "F.Fab")
			(effects
				(font
					(size 1.27 1.27)
				)
			)
		)
		(duplicate_pad_numbers_are_jumpers no)
		(fp_line
			(start 0.7874 -0.4064)
			(end 0.7874 0.4064)
			(stroke
				(width 0.1524)
				(type default)
			)
			(layer "F.SilkS")
		)
		(fp_line
			(start -0.7874 -0.4064)
			(end 0.7874 -0.4064)
			(stroke
				(width 0.1524)
				(type default)
			)
			(layer "F.SilkS")
		)
		(fp_line
			(start 0.7874 0.4064)
			(end -0.7874 0.4064)
			(stroke
				(width 0.1524)
				(type default)
			)
			(layer "F.SilkS")
		)
		(fp_line
			(start -0.7874 0.4064)
			(end -0.7874 -0.4064)
			(stroke
				(width 0.1524)
				(type default)
			)
			(layer "F.SilkS")
		)
		(fp_line
			(start -0.12065 -0.305054)
			(end -0.12065 -0.2794)
			(stroke
				(width 0.1)
				(type default)
			)
			(layer "F.Fab")
		)
		(fp_line
			(start -0.67945 -0.305054)
			(end -0.12065 -0.305054)
			(stroke
				(width 0.1)
				(type default)
			)
			(layer "F.Fab")
		)
		(fp_line
			(start 0.67945 -0.3048)
			(end 0.67945 0.3048)
			(stroke
				(width 0.1)
				(type default)
			)
			(layer "F.Fab")
		)
		(fp_line
			(start 0.12065 -0.3048)
			(end 0.67945 -0.3048)
			(stroke
				(width 0.1)
				(type default)
			)
			(layer "F.Fab")
		)
		(fp_line
			(start 0.12065 -0.2794)
			(end 0.12065 -0.3048)
			(stroke
				(width 0.1)
				(type default)
			)
			(layer "F.Fab")
		)
		(fp_line
			(start -0.12065 -0.2794)
			(end 0.12065 -0.2794)
			(stroke
				(width 0.1)
				(type default)
			)
			(layer "F.Fab")
		)
		(fp_line
			(start 0.120396 0.2794)
			(end -0.12065 0.2794)
			(stroke
				(width 0.1)
				(type default)
			)
			(layer "F.Fab")
		)
		(fp_line
			(start -0.12065 0.2794)
			(end -0.12065 0.3048)
			(stroke
				(width 0.1)
				(type default)
			)
			(layer "F.Fab")
		)
		(fp_line
			(start 0.67945 0.3048)
			(end 0.120396 0.3048)
			(stroke
				(width 0.1)
				(type default)
			)
			(layer "F.Fab")
		)
		(fp_line
			(start 0.120396 0.3048)
			(end 0.120396 0.2794)
			(stroke
				(width 0.1)
				(type default)
			)
			(layer "F.Fab")
		)
		(fp_line
			(start -0.12065 0.3048)
			(end -0.67945 0.3048)
			(stroke
				(width 0.1)
				(type default)
			)
			(layer "F.Fab")
		)
		(fp_line
			(start -0.67945 0.3048)
			(end -0.67945 -0.305054)
			(stroke
				(width 0.1)
				(type default)
			)
			(layer "F.Fab")
		)
		(pad "1" smd circle
			(at -0.40005 0 90)
			(size 0 0)
			(layers "F.Cu" "F.Mask" "F.Paste")
			(net "P3V3_NIC5")
		)
		(pad "2" smd circle
			(at 0.40005 0 90)
			(size 0 0)
			(layers "F.Cu" "F.Mask" "F.Paste")
			(net "NIC5_PWRBRK_N")
		)
	)
	(footprint ""
		(layer "F.Cu")
		(at 129.690114 -254.194564 180)
		(property "Reference" "R825"
			(at 0 0 180)
			(layer "F.SilkS")
			(hide yes)
			(effects
				(font
					(size 1.27 1.27)
				)
			)
		)
		(property "Value" ""
			(at 0 0 180)
			(layer "F.Fab")
			(effects
				(font
					(size 1.27 1.27)
				)
			)
		)
		(duplicate_pad_numbers_are_jumpers no)
		(fp_line
			(start 0.7874 0.4064)
			(end -0.7874 0.4064)
			(stroke
				(width 0.1524)
				(type default)
			)
			(layer "F.SilkS")
		)
		(fp_line
			(start 0.7874 -0.4064)
			(end 0.7874 0.4064)
			(stroke
				(width 0.1524)
				(type default)
			)
			(layer "F.SilkS")
		)
		(fp_line
			(start -0.7874 0.4064)
			(end -0.7874 -0.4064)
			(stroke
				(width 0.1524)
				(type default)
			)
			(layer "F.SilkS")
		)
		(fp_line
			(start -0.7874 -0.4064)
			(end 0.7874 -0.4064)
			(stroke
				(width 0.1524)
				(type default)
			)
			(layer "F.SilkS")
		)
		(fp_line
			(start 0.67945 0.3048)
			(end 0.120396 0.3048)
			(stroke
				(width 0.1)
				(type default)
			)
			(layer "F.Fab")
		)
		(fp_line
			(start 0.67945 -0.3048)
			(end 0.67945 0.3048)
			(stroke
				(width 0.1)
				(type default)
			)
			(layer "F.Fab")
		)
		(fp_line
			(start 0.12065 -0.2794)
			(end 0.12065 -0.3048)
			(stroke
				(width 0.1)
				(type default)
			)
			(layer "F.Fab")
		)
		(fp_line
			(start 0.12065 -0.3048)
			(end 0.67945 -0.3048)
			(stroke
				(width 0.1)
				(type default)
			)
			(layer "F.Fab")
		)
		(fp_line
			(start 0.120396 0.3048)
			(end 0.120396 0.2794)
			(stroke
				(width 0.1)
				(type default)
			)
			(layer "F.Fab")
		)
		(fp_line
			(start 0.120396 0.2794)
			(end -0.12065 0.2794)
			(stroke
				(width 0.1)
				(type default)
			)
			(layer "F.Fab")
		)
		(fp_line
			(start -0.12065 0.3048)
			(end -0.67945 0.3048)
			(stroke
				(width 0.1)
				(type default)
			)
			(layer "F.Fab")
		)
		(fp_line
			(start -0.12065 0.2794)
			(end -0.12065 0.3048)
			(stroke
				(width 0.1)
				(type default)
			)
			(layer "F.Fab")
		)
		(fp_line
			(start -0.12065 -0.2794)
			(end 0.12065 -0.2794)
			(stroke
				(width 0.1)
				(type default)
			)
			(layer "F.Fab")
		)
		(fp_line
			(start -0.12065 -0.305054)
			(end -0.12065 -0.2794)
			(stroke
				(width 0.1)
				(type default)
			)
			(layer "F.Fab")
		)
		(fp_line
			(start -0.67945 0.3048)
			(end -0.67945 -0.305054)
			(stroke
				(width 0.1)
				(type default)
			)
			(layer "F.Fab")
		)
		(fp_line
			(start -0.67945 -0.305054)
			(end -0.12065 -0.305054)
			(stroke
				(width 0.1)
				(type default)
			)
			(layer "F.Fab")
		)
		(pad "1" smd circle
			(at -0.40005 0 180)
			(size 0 0)
			(layers "F.Cu" "F.Mask" "F.Paste")
			(net "P3V3_AUX")
		)
		(pad "2" smd circle
			(at 0.40005 0 180)
			(size 0 0)
			(layers "F.Cu" "F.Mask" "F.Paste")
			(net "P0V8_PEX0_AVRRDY")
		)
	)
	(footprint ""
		(layer "F.Cu")
		(at 112.470184 -280.44902 -90)
		(property "Reference" "PC82"
			(at 0 0 270)
			(layer "F.SilkS")
			(hide yes)
			(effects
				(font
					(size 1.27 1.27)
				)
			)
		)
		(property "Value" ""
			(at 0 0 270)
			(layer "F.Fab")
			(effects
				(font
					(size 1.27 1.27)
				)
			)
		)
		(duplicate_pad_numbers_are_jumpers no)
		(fp_line
			(start -0.7874 0.4064)
			(end -0.7874 -0.4064)
			(stroke
				(width 0.1524)
				(type default)
			)
			(layer "F.SilkS")
		)
		(fp_line
			(start 0.7874 0.4064)
			(end -0.7874 0.4064)
			(stroke
				(width 0.1524)
				(type default)
			)
			(layer "F.SilkS")
		)
		(fp_line
			(start -0.7874 -0.4064)
			(end 0.7874 -0.4064)
			(stroke
				(width 0.1524)
				(type default)
			)
			(layer "F.SilkS")
		)
		(fp_line
			(start 0.7874 -0.4064)
			(end 0.7874 0.4064)
			(stroke
				(width 0.1524)
				(type default)
			)
			(layer "F.SilkS")
		)
		(fp_line
			(start -0.67945 0.3048)
			(end -0.67945 -0.305054)
			(stroke
				(width 0.1)
				(type default)
			)
			(layer "F.Fab")
		)
		(fp_line
			(start -0.12065 0.3048)
			(end -0.67945 0.3048)
			(stroke
				(width 0.1)
				(type default)
			)
			(layer "F.Fab")
		)
		(fp_line
			(start 0.120396 0.3048)
			(end 0.120396 0.2794)
			(stroke
				(width 0.1)
				(type default)
			)
			(layer "F.Fab")
		)
		(fp_line
			(start 0.67945 0.3048)
			(end 0.120396 0.3048)
			(stroke
				(width 0.1)
				(type default)
			)
			(layer "F.Fab")
		)
		(fp_line
			(start -0.12065 0.2794)
			(end -0.12065 0.3048)
			(stroke
				(width 0.1)
				(type default)
			)
			(layer "F.Fab")
		)
		(fp_line
			(start 0.120396 0.2794)
			(end -0.12065 0.2794)
			(stroke
				(width 0.1)
				(type default)
			)
			(layer "F.Fab")
		)
		(fp_line
			(start -0.12065 -0.2794)
			(end 0.12065 -0.2794)
			(stroke
				(width 0.1)
				(type default)
			)
			(layer "F.Fab")
		)
		(fp_line
			(start 0.12065 -0.2794)
			(end 0.12065 -0.3048)
			(stroke
				(width 0.1)
				(type default)
			)
			(layer "F.Fab")
		)
		(fp_line
			(start 0.12065 -0.3048)
			(end 0.67945 -0.3048)
			(stroke
				(width 0.1)
				(type default)
			)
			(layer "F.Fab")
		)
		(fp_line
			(start 0.67945 -0.3048)
			(end 0.67945 0.3048)
			(stroke
				(width 0.1)
				(type default)
			)
			(layer "F.Fab")
		)
		(fp_line
			(start -0.67945 -0.305054)
			(end -0.12065 -0.305054)
			(stroke
				(width 0.1)
				(type default)
			)
			(layer "F.Fab")
		)
		(fp_line
			(start -0.12065 -0.305054)
			(end -0.12065 -0.2794)
			(stroke
				(width 0.1)
				(type default)
			)
			(layer "F.Fab")
		)
		(pad "1" smd circle
			(at -0.40005 0 270)
			(size 0 0)
			(layers "F.Cu" "F.Mask" "F.Paste")
			(net "SW_P0V8_PEX0_PHASE2")
		)
		(pad "2" smd circle
			(at 0.40005 0 270)
			(size 0 0)
			(layers "F.Cu" "F.Mask" "F.Paste")
			(net "SW_P0V8_PEX0_BOOT2_R")
		)
	)
	(footprint ""
		(layer "F.Cu")
		(at 218.963494 -183.55818)
		(property "Reference" "R5500"
			(at 0 0 0)
			(layer "F.SilkS")
			(hide yes)
			(effects
				(font
					(size 1.27 1.27)
				)
			)
		)
		(property "Value" ""
			(at 0 0 0)
			(layer "F.Fab")
			(effects
				(font
					(size 1.27 1.27)
				)
			)
		)
		(duplicate_pad_numbers_are_jumpers no)
		(fp_line
			(start -0.7874 -0.4064)
			(end 0.7874 -0.4064)
			(stroke
				(width 0.1524)
				(type default)
			)
			(layer "F.SilkS")
		)
		(fp_line
			(start -0.7874 0.4064)
			(end -0.7874 -0.4064)
			(stroke
				(width 0.1524)
				(type default)
			)
			(layer "F.SilkS")
		)
		(fp_line
			(start 0.7874 -0.4064)
			(end 0.7874 0.4064)
			(stroke
				(width 0.1524)
				(type default)
			)
			(layer "F.SilkS")
		)
		(fp_line
			(start 0.7874 0.4064)
			(end -0.7874 0.4064)
			(stroke
				(width 0.1524)
				(type default)
			)
			(layer "F.SilkS")
		)
		(fp_line
			(start -0.67945 -0.305054)
			(end -0.12065 -0.305054)
			(stroke
				(width 0.1)
				(type default)
			)
			(layer "F.Fab")
		)
		(fp_line
			(start -0.67945 0.3048)
			(end -0.67945 -0.305054)
			(stroke
				(width 0.1)
				(type default)
			)
			(layer "F.Fab")
		)
		(fp_line
			(start -0.12065 -0.305054)
			(end -0.12065 -0.2794)
			(stroke
				(width 0.1)
				(type default)
			)
			(layer "F.Fab")
		)
		(fp_line
			(start -0.12065 -0.2794)
			(end 0.12065 -0.2794)
			(stroke
				(width 0.1)
				(type default)
			)
			(layer "F.Fab")
		)
		(fp_line
			(start -0.12065 0.2794)
			(end -0.12065 0.3048)
			(stroke
				(width 0.1)
				(type default)
			)
			(layer "F.Fab")
		)
		(fp_line
			(start -0.12065 0.3048)
			(end -0.67945 0.3048)
			(stroke
				(width 0.1)
				(type default)
			)
			(layer "F.Fab")
		)
		(fp_line
			(start 0.120396 0.2794)
			(end -0.12065 0.2794)
			(stroke
				(width 0.1)
				(type default)
			)
			(layer "F.Fab")
		)
		(fp_line
			(start 0.120396 0.3048)
			(end 0.120396 0.2794)
			(stroke
				(width 0.1)
				(type default)
			)
			(layer "F.Fab")
		)
		(fp_line
			(start 0.12065 -0.3048)
			(end 0.67945 -0.3048)
			(stroke
				(width 0.1)
				(type default)
			)
			(layer "F.Fab")
		)
		(fp_line
			(start 0.12065 -0.2794)
			(end 0.12065 -0.3048)
			(stroke
				(width 0.1)
				(type default)
			)
			(layer "F.Fab")
		)
		(fp_line
			(start 0.67945 -0.3048)
			(end 0.67945 0.3048)
			(stroke
				(width 0.1)
				(type default)
			)
			(layer "F.Fab")
		)
		(fp_line
			(start 0.67945 0.3048)
			(end 0.120396 0.3048)
			(stroke
				(width 0.1)
				(type default)
			)
			(layer "F.Fab")
		)
		(pad "1" smd circle
			(at -0.40005 0)
			(size 0 0)
			(layers "F.Cu" "F.Mask" "F.Paste")
			(net "RST_BIC_SRST_R_N")
		)
		(pad "2" smd circle
			(at 0.40005 0)
			(size 0 0)
			(layers "F.Cu" "F.Mask" "F.Paste")
			(net "RST_BIC_BUF_RSMRST_N")
		)
	)
	(footprint ""
		(layer "F.Cu")
		(at 16.02486 -409.848558 -90)
		(property "Reference" "C3652"
			(at 0 0 270)
			(layer "F.SilkS")
			(hide yes)
			(effects
				(font
					(size 1.27 1.27)
				)
			)
		)
		(property "Value" ""
			(at 0 0 270)
			(layer "F.Fab")
			(effects
				(font
					(size 1.27 1.27)
				)
			)
		)
		(duplicate_pad_numbers_are_jumpers no)
		(fp_line
			(start -0.7874 0.4064)
			(end -0.7874 -0.4064)
			(stroke
				(width 0.1524)
				(type default)
			)
			(layer "F.SilkS")
		)
		(fp_line
			(start 0.7874 0.4064)
			(end -0.7874 0.4064)
			(stroke
				(width 0.1524)
				(type default)
			)
			(layer "F.SilkS")
		)
		(fp_line
			(start -0.7874 -0.4064)
			(end 0.7874 -0.4064)
			(stroke
				(width 0.1524)
				(type default)
			)
			(layer "F.SilkS")
		)
		(fp_line
			(start 0.7874 -0.4064)
			(end 0.7874 0.4064)
			(stroke
				(width 0.1524)
				(type default)
			)
			(layer "F.SilkS")
		)
		(fp_line
			(start -0.67945 0.3048)
			(end -0.67945 -0.305054)
			(stroke
				(width 0.1)
				(type default)
			)
			(layer "F.Fab")
		)
		(fp_line
			(start -0.12065 0.3048)
			(end -0.67945 0.3048)
			(stroke
				(width 0.1)
				(type default)
			)
			(layer "F.Fab")
		)
		(fp_line
			(start 0.120396 0.3048)
			(end 0.120396 0.2794)
			(stroke
				(width 0.1)
				(type default)
			)
			(layer "F.Fab")
		)
		(fp_line
			(start 0.67945 0.3048)
			(end 0.120396 0.3048)
			(stroke
				(width 0.1)
				(type default)
			)
			(layer "F.Fab")
		)
		(fp_line
			(start -0.12065 0.2794)
			(end -0.12065 0.3048)
			(stroke
				(width 0.1)
				(type default)
			)
			(layer "F.Fab")
		)
		(fp_line
			(start 0.120396 0.2794)
			(end -0.12065 0.2794)
			(stroke
				(width 0.1)
				(type default)
			)
			(layer "F.Fab")
		)
		(fp_line
			(start -0.12065 -0.2794)
			(end 0.12065 -0.2794)
			(stroke
				(width 0.1)
				(type default)
			)
			(layer "F.Fab")
		)
		(fp_line
			(start 0.12065 -0.2794)
			(end 0.12065 -0.3048)
			(stroke
				(width 0.1)
				(type default)
			)
			(layer "F.Fab")
		)
		(fp_line
			(start 0.12065 -0.3048)
			(end 0.67945 -0.3048)
			(stroke
				(width 0.1)
				(type default)
			)
			(layer "F.Fab")
		)
		(fp_line
			(start 0.67945 -0.3048)
			(end 0.67945 0.3048)
			(stroke
				(width 0.1)
				(type default)
			)
			(layer "F.Fab")
		)
		(fp_line
			(start -0.67945 -0.305054)
			(end -0.12065 -0.305054)
			(stroke
				(width 0.1)
				(type default)
			)
			(layer "F.Fab")
		)
		(fp_line
			(start -0.12065 -0.305054)
			(end -0.12065 -0.2794)
			(stroke
				(width 0.1)
				(type default)
			)
			(layer "F.Fab")
		)
		(pad "1" smd circle
			(at -0.40005 0 270)
			(size 0 0)
			(layers "F.Cu" "F.Mask" "F.Paste")
			(net "P3V3_AUX")
		)
		(pad "2" smd circle
			(at 0.40005 0 270)
			(size 0 0)
			(layers "F.Cu" "F.Mask" "F.Paste")
			(net "GND")
		)
	)
	(footprint ""
		(layer "F.Cu")
		(at 95.105728 -246.840248 180)
		(property "Reference" "R813"
			(at 0 0 180)
			(layer "F.SilkS")
			(hide yes)
			(effects
				(font
					(size 1.27 1.27)
				)
			)
		)
		(property "Value" ""
			(at 0 0 180)
			(layer "F.Fab")
			(effects
				(font
					(size 1.27 1.27)
				)
			)
		)
		(duplicate_pad_numbers_are_jumpers no)
		(fp_line
			(start 0.7874 0.4064)
			(end -0.7874 0.4064)
			(stroke
				(width 0.1524)
				(type default)
			)
			(layer "F.SilkS")
		)
		(fp_line
			(start 0.7874 -0.4064)
			(end 0.7874 0.4064)
			(stroke
				(width 0.1524)
				(type default)
			)
			(layer "F.SilkS")
		)
		(fp_line
			(start -0.7874 0.4064)
			(end -0.7874 -0.4064)
			(stroke
				(width 0.1524)
				(type default)
			)
			(layer "F.SilkS")
		)
		(fp_line
			(start -0.7874 -0.4064)
			(end 0.7874 -0.4064)
			(stroke
				(width 0.1524)
				(type default)
			)
			(layer "F.SilkS")
		)
		(fp_line
			(start 0.67945 0.3048)
			(end 0.120396 0.3048)
			(stroke
				(width 0.1)
				(type default)
			)
			(layer "F.Fab")
		)
		(fp_line
			(start 0.67945 -0.3048)
			(end 0.67945 0.3048)
			(stroke
				(width 0.1)
				(type default)
			)
			(layer "F.Fab")
		)
		(fp_line
			(start 0.12065 -0.2794)
			(end 0.12065 -0.3048)
			(stroke
				(width 0.1)
				(type default)
			)
			(layer "F.Fab")
		)
		(fp_line
			(start 0.12065 -0.3048)
			(end 0.67945 -0.3048)
			(stroke
				(width 0.1)
				(type default)
			)
			(layer "F.Fab")
		)
		(fp_line
			(start 0.120396 0.3048)
			(end 0.120396 0.2794)
			(stroke
				(width 0.1)
				(type default)
			)
			(layer "F.Fab")
		)
		(fp_line
			(start 0.120396 0.2794)
			(end -0.12065 0.2794)
			(stroke
				(width 0.1)
				(type default)
			)
			(layer "F.Fab")
		)
		(fp_line
			(start -0.12065 0.3048)
			(end -0.67945 0.3048)
			(stroke
				(width 0.1)
				(type default)
			)
			(layer "F.Fab")
		)
		(fp_line
			(start -0.12065 0.2794)
			(end -0.12065 0.3048)
			(stroke
				(width 0.1)
				(type default)
			)
			(layer "F.Fab")
		)
		(fp_line
			(start -0.12065 -0.2794)
			(end 0.12065 -0.2794)
			(stroke
				(width 0.1)
				(type default)
			)
			(layer "F.Fab")
		)
		(fp_line
			(start -0.12065 -0.305054)
			(end -0.12065 -0.2794)
			(stroke
				(width 0.1)
				(type default)
			)
			(layer "F.Fab")
		)
		(fp_line
			(start -0.67945 0.3048)
			(end -0.67945 -0.305054)
			(stroke
				(width 0.1)
				(type default)
			)
			(layer "F.Fab")
		)
		(fp_line
			(start -0.67945 -0.305054)
			(end -0.12065 -0.305054)
			(stroke
				(width 0.1)
				(type default)
			)
			(layer "F.Fab")
		)
		(pad "1" smd circle
			(at -0.40005 0 180)
			(size 0 0)
			(layers "F.Cu" "F.Mask" "F.Paste")
			(net "PEX_P1V8_ADC_A1")
		)
		(pad "2" smd circle
			(at 0.40005 0 180)
			(size 0 0)
			(layers "F.Cu" "F.Mask" "F.Paste")
			(net "P3V3_AUX")
		)
	)
)
